# S9S_MB_2U (Grand Teton) — schematic parts with pin connectivity, parts 5289–5444 of 6093; source: Cadence DE-HDL packaged netlist (pstxprt.dat, pstxnet.dat, pstchip.dat)

R4046  Q_RES  33.2 1% CHIP  pkg 0402LF  page 225 : 1 = RST_CPU1_DRAM_AB_PLD_LVT3_R_N ; 2 = RST_CPU1_DRAM_AB_PLD_LVT3_N
R4047  Q_RES  33.2 1% CHIP  pkg 0402LF  page 225 : 1 = RST_CPU1_DRAM_CD_PLD_LVT3_R_N ; 2 = RST_CPU1_DRAM_CD_PLD_LVT3_N
R4048  Q_RES  33.2 1% CHIP  pkg 0402LF  page 225 : 1 = RST_CPU1_DRAM_EF_PLD_LVT3_R_N ; 2 = RST_CPU1_DRAM_EF_PLD_LVT3_N
R4049  Q_RES  33.2 1% CHIP  pkg 0402LF  page 225 : 1 = RST_CPU1_DRAM_GH_PLD_LVT3_R_N ; 2 = RST_CPU1_DRAM_GH_PLD_LVT3_N
R4050  Q_RES  33.2 1% CHIP  pkg 0402LF  page 225 : 1 = H_CPU_ERR0_LVC2_R_N ; 2 = H_CPU_ERR0_LVC2_N
R4051  Q_RES  33.2 1% CHIP  pkg 0402LF  page 225 : 1 = H_CPU_ERR1_LVC2_R_N ; 2 = H_CPU_ERR1_LVC2_N
R4052  Q_RES  33.2 1% CHIP  pkg 0402LF  page 225 : 1 = H_CPU_ERR2_LVC2_R_N ; 2 = H_CPU_ERR2_LVC2_N
R4053  Q_RES  1K 1% CHIP  pkg 0402LF  page 225 : 1 = PD_GTL2014_BMC_JTAG_DIR_0 ; 2 = GND
R4054  Q_RES  1K 1% CHIP  pkg 0402LF  page 225 : 1 = PD_GTL2014_BMC_JTAG_DIR_1 ; 2 = GND
R4055  Q_RES  1K 1% CHIP  pkg 0402LF  page 225 : 1 = PD_CPU1_ERRS_U306_DIR ; 2 = GND
R4056  Q_RES  0 5% CHIP  pkg 0402LF  page 215 : 1 = HSC_D_OC ; 2 = HSC_D_OC_R1
R4057  Q_RES  33.2 1% CHIP  pkg 0402LF  page 215 : 1 = PRSNT_SWB_ISO_N ; 2 = PRSNT_SWB_ISO_R_N
R4059  Q_RES  0 5% EMPTY  pkg 0402LF  page 162 : 1 = HP_LVC3_OCP_V3_2_EN ; 2 = P12V_OCP_EN_2_R
R4060  Q_RES  0 5% CHIP  pkg 0402LF  page 162 : 1 = HP_LVC3_OCP_V3_2_EN ; 2 = P3V3_OCP_EN_2_R
R4061  Q_RES  0 5% EMPTY  pkg 0402LF  page 156 : 1 = HP_LVC3_OCP_V3_1_EN ; 2 = P12V_OCP_EN_1_R
R4062  Q_RES  0 5% EMPTY  pkg 0402LF  page 242 : 1 = P12V_SCM_EN ; 2 = P12V_SCM_EN_R
R4063  Q_RES  0 5% CHIP  pkg 0402LF  page 192 : 1 = E1S_0_EN ; 2 = P3V3_E1S_EN_1_R
R4064  Q_RES  0 5% CHIP  pkg 0402LF  page 192 : 1 = E1S_0_EN ; 2 = P12V_E1S_EN_0_R
R4065  Q_RES  10K 1% EMPTY  pkg 0402LF  page 162 : 1 = P12V_AUX ; 2 = P12V_OCP_2_EN_G
R4066  Q_RES  4.7K 5% CHIP  pkg 0402LF  page 162 : 1 = P3V3_OCP_EN_2_R ; 2 = GND
R4067  Q_RES  10K 1% CHIP  pkg 0402LF  page 162 : 1 = P12V_AUX ; 2 = P3V3_OCP_2_EN_G
R4068  Q_RES  10K 1% EMPTY  pkg 0402LF  page 156 : 1 = P12V_AUX ; 2 = P12V_OCP_1_EN_G
R4069  Q_RES  4.7K 5% CHIP  pkg 0402LF  page 156 : 1 = P3V3_OCP_EN_1_R ; 2 = GND
R4070  Q_RES  10K 1% CHIP  pkg 0402LF  page 156 : 1 = P12V_AUX ; 2 = P3V3_OCP_1_EN_G
R4071  Q_RES  10K 1% EMPTY  pkg 0402LF  page 242 : 1 = P12V_AUX ; 2 = P12V_SCM_EN_G
R4072  Q_RES  10K 1% CHIP  pkg 0402LF  page 192 : 1 = P12V_AUX ; 2 = P3V3_E1S_0_EN_G
R4073  Q_RES  4.7K 5% CHIP  pkg 0402LF  page 192 : 1 = P12V_E1S_EN_0_R ; 2 = GND
R4074  Q_RES  10K 1% EMPTY  pkg 0402LF  page 192 : 1 = P12V_AUX ; 2 = P12V_E1S_0_EN_G
R4075  Q_RES  0 5% CHIP  pkg 0402LF  page 212 : 1 = CLK_GEN2_BMC_RC_OE_N ; 2 = CLK_GEN2_BMC_RC_OE_R3_N
R4076  Q_RES  0 5% CHIP  pkg 0402LF  page 212 : 1 = CLK_GEN2_GPU_FPGA_OE_OR_N ; 2 = CLK_GEN2_GPU_OE_N
R4077  Q_RES  1 1% CHIP  pkg 0402LF  page 212 : 1 = VFG3P3_CLK_GEN ; 2 = VFG_3P3A_CLK_GEN
R4078  Q_RES  10K 1% EMPTY  pkg 0402LF  page 212 : 1 = P3V3_AUX ; 2 = FG_SS_EN
R4079  Q_RES  10K 1% CHIP  pkg 0402LF  page 212 : 1 = FG_SS_EN ; 2 = GND
R4080  Q_RES  10K 1% CHIP  pkg 0402LF  page 212 : 1 = P3V3_AUX ; 2 = P3V3_PWRGD_CLKGEN
R4081  Q_RES  10K 1% CHIP  pkg 0402LF  page 212 : 1 = P3V3_AUX ; 2 = CLK_GEN2_SMB_SADR
R4082  Q_RES  10K 1% EMPTY  pkg 0402LF  page 212 : 1 = CLK_GEN2_SMB_SADR ; 2 = GND
R4083  Q_RES  0 5% EMPTY  pkg 0402LF  page 183 : 1 = E1S_0_PERST1_CLKREQ_N ; 2 = E1S_0_CLKREQ_N
R4084  Q_RES  0 5% EMPTY  pkg 0402LF  page 183 : 1 = E1S_0_PRSNT_N ; 2 = E1S_0_CLKREQ_N
R4086  Q_RES  10K 1% CHIP  pkg 0402LF  page 215 : 1 = P3V3_AUX_FPGA_VCCIO2 ; 2 = PULL_FPGA_PB46A
R4087  Q_RES  33.2 1% CHIP  pkg 0402LF  page 240 : 1 = FM_JTAG_BMC_MUX_SEL_FROM_BMC_R ; 2 = FM_JTAG_BMC_MUX_SEL_FROM_BMC_R2
R4088  Q_RES  0 5% CHIP  pkg 0402LF  page 214 : 1 = FM_JTAG_BMC_MUX_SEL_FROM_BMC_R ; 2 = FM_JTAG_BMC_MUX_SEL
R4089  Q_RES  33.2 1% CHIP  pkg 0402LF  page 14 : 1 = H_CPU0_PMSYNC_CPU1_R1 ; 2 = H_CPU0_PMSYNC_CPU1
R4090  Q_RES  4.7K 1% CHIP  pkg 0402LF  page 172 : 1 = P3V3_AUX ; 2 = M2_0_P3V3_ADC_ALERT_R
R4091  Q_RES  4.7K 1% CHIP  pkg 0402LF  page 172 : 1 = P3V3_AUX ; 2 = P12V_SCM_ADC_ALERT_R
R4092  Q_RES  4.7K 1% CHIP  pkg 0402LF  page 172 : 1 = P3V3_AUX ; 2 = OCP_V3_2_P3V3_ADC_ALERT_R
R4093  Q_RES  4.7K 1% CHIP  pkg 0402LF  page 171 : 1 = P3V3_AUX ; 2 = E1S_0_P3V3_ADC_ALERT_R
R4094  Q_RES  4.7K 1% CHIP  pkg 0402LF  page 171 : 1 = P3V3_AUX ; 2 = OCP_SFF_P3V3_ADC_ALERT_R
R4095  Q_RES  10K 1% CHIP  pkg 0402LF  page 183 : 1 = PD_PCH_GPPC_A_19 ; 2 = GND
R4096  Q_RES  10K 1% CHIP  pkg 0402LF  page 183 : 1 = PD_PCH_GPPC_A_18 ; 2 = GND
R4097  Q_RES  10K 1% CHIP  pkg 0402LF  page 183 : 1 = PD_PCH_GPPC_A_15 ; 2 = GND
R4098  Q_RES  10K 1% CHIP  pkg 0402LF  page 183 : 1 = PD_PCH_GPPC_A_14 ; 2 = GND
R4099  Q_RES  10K 1% CHIP  pkg 0402LF  page 183 : 1 = PD_PCH_GPPC_A_10 ; 2 = GND
R4100  Q_RES  10K 1% CHIP  pkg 0402LF  page 183 : 1 = PD_PCH_GPPC_C10 ; 2 = GND
R4101  Q_RES  10K 1% CHIP  pkg 0402LF  page 183 : 1 = PD_PCH_GPPC_C9 ; 2 = GND
R4102  Q_RES  10K 1% CHIP  pkg 0402LF  page 183 : 1 = PD_PCH_GPPC_C5 ; 2 = GND
R4103  Q_RES  10K 1% CHIP  pkg 0402LF  page 184 : 1 = PD_GPP_M_17 ; 2 = GND
R4104  Q_RES  10K 1% CHIP  pkg 0402LF  page 184 : 1 = PD_GPP_M_16 ; 2 = GND
R4105  Q_RES  10K 1% CHIP  pkg 0402LF  page 184 : 1 = PD_GPP_M_15 ; 2 = GND
R4106  Q_RES  10K 1% CHIP  pkg 0402LF  page 184 : 1 = PD_GPP_M_8 ; 2 = GND
R4107  Q_RES  10K 1% CHIP  pkg 0402LF  page 184 : 1 = PD_GPP_I_17 ; 2 = GND
R4108  Q_RES  10K 1% CHIP  pkg 0402LF  page 184 : 1 = PD_GPP_I_16 ; 2 = GND
R4109  Q_RES  10K 1% CHIP  pkg 0402LF  page 184 : 1 = PD_GPP_I_15 ; 2 = GND
R4110  Q_RES  10K 1% CHIP  pkg 0402LF  page 184 : 1 = PD_PCH_GPP_E_14 ; 2 = GND
R4111  Q_RES  10K 1% CHIP  pkg 0402LF  page 184 : 1 = PD_PCH_GPP_E_13 ; 2 = GND
R4112  Q_RES  10K 1% CHIP  pkg 0402LF  page 184 : 1 = PD_PCH_GPP_E_12 ; 2 = GND
R4113  Q_RES  10K 1% CHIP  pkg 0402LF  page 184 : 1 = PD_PCH_GPP_E_11 ; 2 = GND
R4114  Q_RES  10K 1% CHIP  pkg 0402LF  page 184 : 1 = PD_PCH_GPP_E_10 ; 2 = GND
R4115  Q_RES  10K 1% CHIP  pkg 0402LF  page 184 : 1 = PD_PCH_GPP_E_9 ; 2 = GND
R4116  Q_RES  10K 1% CHIP  pkg 0402LF  page 184 : 1 = PD_PCH_GPP_E_8 ; 2 = GND
R4117  Q_RES  10K 1% CHIP  pkg 0402LF  page 184 : 1 = PD_PCH_GPP_E_3 ; 2 = GND
R4118  Q_RES  10 1% CHIP  pkg 0402LF  page 202 : 1 = IRQ_LPC_SERIRQ_ESPI_CS1_N ; 2 = IRQ_LPC_SERIRQ_ESPI_CS1_R_N
R4119  Q_RES  54.9K 1% EMPTY  pkg 0402LF  page 146 : 1 = P3V3_AUX ; 2 = GPU_3V3IO_RSVD0_FFU
R4120  Q_RES  100K 1% EMPTY  pkg 0402LF  page 146 : 1 = GPU_3V3IO_RSVD0_FFU ; 2 = GND
R4121  Q_RES  10K 1% CHIP  pkg 0402LF  page 146 : 1 = P3V3_AUX ; 2 = PRSNT_CABLE_GPU_B3_N
R4122  Q_RES  100K 1% EMPTY  pkg 0402LF  page 146 : 1 = PRSNT_CABLE_GPU_B3_N ; 2 = GND
R4123  Q_RES  54.9K 1% EMPTY  pkg 0402LF  page 146 : 1 = P3V3_AUX ; 2 = GPU_3V3IO_RSVD1_FFU
R4124  Q_RES  100K 1% EMPTY  pkg 0402LF  page 146 : 1 = GPU_3V3IO_RSVD1_FFU ; 2 = GND
R4125  Q_RES  4.7K 5% CHIP  pkg 0402LF  page 146 : 1 = P3V3_AUX ; 2 = GPU_3V3IO_RSVD0_FFU_N
R4126  Q_RES  4.7K 5% CHIP  pkg 0402LF  page 146 : 1 = P3V3_AUX ; 2 = PRSNT_CABLE_GPU_B3
R4127  Q_RES  4.7K 5% CHIP  pkg 0402LF  page 146 : 1 = P3V3_AUX ; 2 = GPU_3V3IO_RSVD1_FFU_N
R4128  Q_RES  4.7K 5% CHIP  pkg 0402LF  page 146 : 1 = P3V3_AUX ; 2 = GPU_3V3IO_RSVD0_FFU_ISO
R4129  Q_RES  4.7K 5% CHIP  pkg 0402LF  page 146 : 1 = P3V3_AUX ; 2 = PRSNT_CABLE_GPU_B3_ISO_N
R4130  Q_RES  4.7K 5% CHIP  pkg 0402LF  page 146 : 1 = P3V3_AUX ; 2 = GPU_3V3IO_RSVD1_FFU_ISO
R4131  Q_RES  54.9K 1% EMPTY  pkg 0402LF  page 146 : 1 = P3V3_AUX ; 2 = GPU_3V3IO_RSVD3_FFU
R4132  Q_RES  100K 1% EMPTY  pkg 0402LF  page 146 : 1 = GPU_3V3IO_RSVD3_FFU ; 2 = GND
R4133  Q_RES  54.9K 1% EMPTY  pkg 0402LF  page 146 : 1 = P3V3_AUX ; 2 = GPU_3V3IO_RSVD5_FFU
R4134  Q_RES  100K 1% EMPTY  pkg 0402LF  page 146 : 1 = GPU_3V3IO_RSVD5_FFU ; 2 = GND
R4135  Q_RES  10K 1% CHIP  pkg 0402LF  page 146 : 1 = P3V3_AUX ; 2 = PRSNT_CABLE_GPU_A2_N
R4136  Q_RES  100K 1% EMPTY  pkg 0402LF  page 146 : 1 = PRSNT_CABLE_GPU_A2_N ; 2 = GND
R4137  Q_RES  4.7K 5% CHIP  pkg 0402LF  page 146 : 1 = P3V3_AUX ; 2 = GPU_3V3IO_RSVD3_FFU_N
R4138  Q_RES  4.7K 5% CHIP  pkg 0402LF  page 146 : 1 = P3V3_AUX ; 2 = GPU_3V3IO_RSVD5_FFU_N
R4139  Q_RES  4.7K 5% CHIP  pkg 0402LF  page 146 : 1 = P3V3_AUX ; 2 = PRSNT_CABLE_GPU_A2
R4140  Q_RES  4.7K 5% CHIP  pkg 0402LF  page 146 : 1 = P3V3_AUX ; 2 = GPU_3V3IO_RSVD3_FFU_ISO
R4141  Q_RES  4.7K 5% CHIP  pkg 0402LF  page 146 : 1 = P3V3_AUX ; 2 = GPU_3V3IO_RSVD5_FFU_ISO
R4142  Q_RES  4.7K 5% CHIP  pkg 0402LF  page 146 : 1 = P3V3_AUX ; 2 = PRSNT_CABLE_GPU_A2_ISO_N
R4143  Q_RES  33.2 1% CHIP  pkg 0402LF  page 215 : 1 = GPU_3V3IO_RSVD0_FFU_ISO ; 2 = GPU_3V3IO_RSVD0_FFU_ISO_R
R4144  Q_RES  33.2 1% CHIP  pkg 0402LF  page 215 : 1 = GPU_3V3IO_RSVD1_FFU_ISO ; 2 = GPU_3V3IO_RSVD1_FFU_ISO_R
R4145  Q_RES  33.2 1% CHIP  pkg 0402LF  page 215 : 1 = PRSNT_CABLE_GPU_B3_ISO_N ; 2 = PRSNT_CABLE_GPU_B3_ISO_R_N
R4146  Q_RES  33.2 1% CHIP  pkg 0402LF  page 215 : 1 = GPU_3V3IO_RSVD3_FFU_ISO ; 2 = GPU_3V3IO_RSVD3_FFU_ISO_R
R4147  Q_RES  33.2 1% CHIP  pkg 0402LF  page 215 : 1 = PRSNT_CABLE_GPU_A2_ISO_N ; 2 = PRSNT_CABLE_GPU_A2_ISO_R_N
R4148  Q_RES  33.2 1% CHIP  pkg 0402LF  page 215 : 1 = GPU_3V3IO_RSVD5_FFU_ISO ; 2 = GPU_3V3IO_RSVD5_FFU_ISO_R
R4149  Q_RES  33.2 1% CHIP  pkg 0402LF  page 241 : 1 = SMB_1_PLD_3V3AUX_SCL ; 2 = SMB_1_PLD_3V3AUX_SCL_R1
R4150  Q_RES  33.2 1% CHIP  pkg 0402LF  page 241 : 1 = SMB_1_PLD_3V3AUX_SDA ; 2 = SMB_1_PLD_3V3AUX_SDA_R1
R4151  Q_RES  33.2 1% CHIP  pkg 0402LF  page 241 : 1 = SMB_1_PLD_3V3AUX_SCL ; 2 = SMB_2_PLD_3V3AUX_SCL_R1
R4152  Q_RES  33.2 1% CHIP  pkg 0402LF  page 241 : 1 = SMB_1_PLD_3V3AUX_SDA ; 2 = SMB_2_PLD_3V3AUX_SDA_R1
R4153  Q_RES  10K 1% CHIP  pkg 0402LF  page 146 : 1 = P3V3_AUX ; 2 = PRSNT_CABLE_GPU_A1_N
R4154  Q_RES  100K 1% EMPTY  pkg 0402LF  page 146 : 1 = PRSNT_CABLE_GPU_A1_N ; 2 = GND
R4155  Q_RES  4.7K 5% CHIP  pkg 0402LF  page 146 : 1 = P3V3_AUX ; 2 = PRSNT_CABLE_GPU_A1
R4156  Q_RES  4.7K 5% CHIP  pkg 0402LF  page 146 : 1 = P3V3_AUX ; 2 = PRSNT_CABLE_GPU_A1_ISO_N
R4157  Q_RES  33.2 1% CHIP  pkg 0402LF  page 215 : 1 = PRSNT_CABLE_GPU_A1_ISO_N ; 2 = PRSNT_CABLE_GPU_A1_ISO_R_N
R4158  Q_RES  54.9K 1% EMPTY  pkg 0402LF  page 145 : 1 = P3V3_AUX ; 2 = GPU_3V3IO_RSVD1
R4159  Q_RES  100K 1% EMPTY  pkg 0402LF  page 145 : 1 = GPU_3V3IO_RSVD1 ; 2 = GND
R4160  Q_RES  54.9K 1% EMPTY  pkg 0402LF  page 145 : 1 = P3V3_AUX ; 2 = GPU_3V3IO_RSVD4
R4161  Q_RES  100K 1% EMPTY  pkg 0402LF  page 145 : 1 = GPU_3V3IO_RSVD4 ; 2 = GND
R4162  Q_RES  54.9K 1% EMPTY  pkg 0402LF  page 145 : 1 = P3V3_AUX ; 2 = GPU_3V3IO_RSVD3
R4163  Q_RES  100K 1% EMPTY  pkg 0402LF  page 145 : 1 = GPU_3V3IO_RSVD3 ; 2 = GND
R4164  Q_RES  4.7K 5% CHIP  pkg 0402LF  page 145 : 1 = P3V3_AUX ; 2 = GPU_3V3IO_RSVD1_N
R4165  Q_RES  4.7K 5% CHIP  pkg 0402LF  page 145 : 1 = P3V3_AUX ; 2 = GPU_3V3IO_RSVD4_N
R4166  Q_RES  4.7K 5% CHIP  pkg 0402LF  page 145 : 1 = P3V3_AUX ; 2 = GPU_3V3IO_RSVD3_N
R4167  Q_RES  4.7K 5% CHIP  pkg 0402LF  page 145 : 1 = P3V3_AUX ; 2 = GPU_3V3IO_RSVD1_ISO
R4168  Q_RES  4.7K 5% CHIP  pkg 0402LF  page 145 : 1 = P3V3_AUX ; 2 = GPU_3V3IO_RSVD4_ISO
R4169  Q_RES  4.7K 5% CHIP  pkg 0402LF  page 145 : 1 = P3V3_AUX ; 2 = GPU_3V3IO_RSVD3_ISO
R4170  Q_RES  33.2 1% CHIP  pkg 0402LF  page 215 : 1 = GPU_3V3IO_RSVD1_ISO ; 2 = GPU_3V3IO_RSVD1_ISO_R
R4171  Q_RES  33.2 1% CHIP  pkg 0402LF  page 215 : 1 = GPU_3V3IO_RSVD3_ISO ; 2 = GPU_3V3IO_RSVD3_ISO_R
R4172  Q_RES  33.2 1% CHIP  pkg 0402LF  page 215 : 1 = GPU_3V3IO_RSVD4_ISO ; 2 = GPU_3V3IO_RSVD4_ISO_R
R4173  Q_RES  100K 1% EMPTY  pkg 0402LF  page 151 : 1 = P3V3_AUX ; 2 = UART_BMC_BIC_R_BUF_RX
R4174  Q_RES  33.2 1% CHIP  pkg 0402LF  page 215 : 1 = RST_PCIE_PCH_DEV_PERST_N ; 2 = RST_PCIE_PCH_DEV_PERST_E1S_R_N
R4175  Q_RES  33.2 1% CHIP  pkg 0402LF  page 215 : 1 = RST_PCIE_PCH_DEV_PERST_N ; 2 = RST_PCIE_PCH_DEV_PERST_M2_R_N
R4176  Q_RES  10K 1% CHIP  pkg 0402LF  page 257 : 1 = P3V3_AUX ; 2 = FM_LPC_ESPI_SEL
R4177  Q_RES  0 5% CHIP  pkg 0402LF  page 257 : 1 = FM_ESPI_PLD_R_EN_BUF_R ; 2 = FM_ESPI_PLD_R_EN_BUF
R4178  Q_RES  33.2 1% CHIP  pkg 0402LF  page 170 : 1 = SMB_LM75_2_3V3AUX_SCL ; 2 = SMB_LM75_2_3V3AUX_SCL_R1
R4179  Q_RES  33.2 1% CHIP  pkg 0402LF  page 170 : 1 = SMB_LM75_1_3V3AUX_SCL ; 2 = SMB_LM75_1_3V3AUX_SCL_R1
R4180  Q_RES  33.2 1% CHIP  pkg 0402LF  page 170 : 1 = SMB_LM75_0_3V3AUX_SCL ; 2 = SMB_LM75_0_3V3AUX_SCL_R1
R4181  Q_RES  33.2 1% CHIP  pkg 0402LF  page 170 : 1 = SMB_LM75_2_3V3AUX_SDA ; 2 = SMB_LM75_2_3V3AUX_SDA_R1
R4182  Q_RES  33.2 1% CHIP  pkg 0402LF  page 170 : 1 = SMB_LM75_1_3V3AUX_SDA ; 2 = SMB_LM75_1_3V3AUX_SDA_R1
R4183  Q_RES  33.2 1% CHIP  pkg 0402LF  page 170 : 1 = SMB_LM75_0_3V3AUX_SDA ; 2 = SMB_LM75_0_3V3AUX_SDA_R1
R4184  Q_RES  1K 1% EMPTY  pkg 0402LF  page 170 : 1 = P3V3_AUX ; 2 = U273_3_ADD2
R4185  Q_RES  1K 1% CHIP  pkg 0402LF  page 170 : 1 = U273_3_ADD2 ; 2 = GND
R4186  Q_RES  1K 1% EMPTY  pkg 0402LF  page 170 : 1 = P3V3_AUX ; 2 = U272_2_ADD2
R4187  Q_RES  1K 1% CHIP  pkg 0402LF  page 170 : 1 = U272_2_ADD2 ; 2 = GND
R4188  Q_RES  1K 1% EMPTY  pkg 0402LF  page 170 : 1 = P3V3_AUX ; 2 = U271_1_ADD2
R4189  Q_RES  1K 1% CHIP  pkg 0402LF  page 170 : 1 = U271_1_ADD2 ; 2 = GND
R4190  Q_RES  1K 1% EMPTY  pkg 0402LF  page 170 : 1 = P3V3_AUX ; 2 = U270_0_ADD2
R4191  Q_RES  1K 1% CHIP  pkg 0402LF  page 170 : 1 = U270_0_ADD2 ; 2 = GND
R4192  Q_RES  1K 1% EMPTY  pkg 0402LF  page 170 : 1 = P3V3_AUX ; 2 = U273_3_ADD1
R4193  Q_RES  1K 1% CHIP  pkg 0402LF  page 170 : 1 = U273_3_ADD1 ; 2 = GND
R4194  Q_RES  1K 1% EMPTY  pkg 0402LF  page 170 : 1 = P3V3_AUX ; 2 = U272_2_ADD1
R4195  Q_RES  1K 1% CHIP  pkg 0402LF  page 170 : 1 = U272_2_ADD1 ; 2 = GND
R4196  Q_RES  1K 1% EMPTY  pkg 0402LF  page 170 : 1 = P3V3_AUX ; 2 = U271_1_ADD1
R4197  Q_RES  1K 1% CHIP  pkg 0402LF  page 170 : 1 = U271_1_ADD1 ; 2 = GND
R4198  Q_RES  1K 1% EMPTY  pkg 0402LF  page 170 : 1 = P3V3_AUX ; 2 = U270_0_ADD1
R4199  Q_RES  1K 1% CHIP  pkg 0402LF  page 170 : 1 = U270_0_ADD1 ; 2 = GND
R4200  Q_RES  1K 1% EMPTY  pkg 0402LF  page 170 : 1 = P3V3_AUX ; 2 = U273_3_ADD0
R4201  Q_RES  1K 1% CHIP  pkg 0402LF  page 170 : 1 = U273_3_ADD0 ; 2 = GND
R4202  Q_RES  1K 1% EMPTY  pkg 0402LF  page 170 : 1 = P3V3_AUX ; 2 = U272_2_ADD0
R4203  Q_RES  1K 1% CHIP  pkg 0402LF  page 170 : 1 = U272_2_ADD0 ; 2 = GND
